(kicad_pcb
	(version 20260206)
	(generator "pcbnew")
	(generator_version "10.0")
	(general
		(thickness 1.6)
		(legacy_teardrops no)
	)
	(paper "A4")
	(title_block
		(title "03242023_DA0F0TMBIJ0_F0T_Motherboard_J_brd_V01_OCP.brd")
		(comment 1 "Grand Teton / footprints 846-853 of 6105")
	)
	(layers
		(0 "F.Cu" signal "TOP")
		(4 "In1.Cu" signal "GND")
		(6 "In2.Cu" signal "IN1")
		(8 "In3.Cu" signal "GND1")
		(10 "In4.Cu" signal "IN2")
		(12 "In5.Cu" signal "GND2")
		(14 "In6.Cu" signal "IN3")
		(16 "In7.Cu" signal "GND3")
		(18 "In8.Cu" signal "VCC")
		(20 "In9.Cu" signal "VCC1")
		(22 "In10.Cu" signal "GND4")
		(24 "In11.Cu" signal "IN4")
		(26 "In12.Cu" signal "GND5")
		(28 "In13.Cu" signal "IN5")
		(30 "In14.Cu" signal "GND6")
		(32 "In15.Cu" signal "IN6")
		(34 "In16.Cu" signal "GND7")
		(2 "B.Cu" signal "BOTTOM")
		(9 "F.Adhes" user "F.Adhesive")
		(11 "B.Adhes" user "B.Adhesive")
		(13 "F.Paste" user "Package Geometry/Pastemask Top")
		(15 "B.Paste" user "Package Geometry/Pastemask Bottom")
		(5 "F.SilkS" user "Ref Des/Silkscreen Top")
		(7 "B.SilkS" user "Ref Des/Silkscreen Bottom")
		(1 "F.Mask" user "Board Geometry/Soldermask Top")
		(3 "B.Mask" user "Board Geometry/Soldermask Bottom")
		(17 "Dwgs.User" user "User.Drawings")
		(19 "Cmts.User" user "User.Comments")
		(21 "Eco1.User" user "User.Eco1")
		(23 "Eco2.User" user "User.Eco2")
		(25 "Edge.Cuts" user "Board Geometry/Outline")
		(27 "Margin" user)
		(31 "F.CrtYd" user "Package Geometry/Place Bound Top")
		(29 "B.CrtYd" user "Package Geometry/Place Bound Bottom")
		(35 "F.Fab" user "Ref Des/Assembly Top")
		(33 "B.Fab" user "Ref Des/Assembly Bottom")
	)
	(footprint ""
		(layer "F.Cu")
		(at 23.392384 -176.82972 -90)
		(property "Reference" "PR2"
			(at 0 0 270)
			(layer "F.SilkS")
			(hide yes)
			(effects
				(font
					(size 1.27 1.27)
				)
			)
		)
		(property "Value" ""
			(at 0 0 270)
			(layer "F.Fab")
			(effects
				(font
					(size 1.27 1.27)
				)
			)
		)
		(duplicate_pad_numbers_are_jumpers no)
		(fp_line
			(start -0.7874 0.4064)
			(end -0.7874 -0.4064)
			(stroke
				(width 0.1524)
				(type default)
			)
			(layer "F.SilkS")
		)
		(fp_line
			(start 0.7874 0.4064)
			(end -0.7874 0.4064)
			(stroke
				(width 0.1524)
				(type default)
			)
			(layer "F.SilkS")
		)
		(fp_line
			(start -0.7874 -0.4064)
			(end 0.7874 -0.4064)
			(stroke
				(width 0.1524)
				(type default)
			)
			(layer "F.SilkS")
		)
		(fp_line
			(start 0.7874 -0.4064)
			(end 0.7874 0.4064)
			(stroke
				(width 0.1524)
				(type default)
			)
			(layer "F.SilkS")
		)
		(fp_line
			(start -0.67945 0.3048)
			(end -0.67945 -0.305054)
			(stroke
				(width 0.1)
				(type default)
			)
			(layer "F.Fab")
		)
		(fp_line
			(start -0.12065 0.3048)
			(end -0.67945 0.3048)
			(stroke
				(width 0.1)
				(type default)
			)
			(layer "F.Fab")
		)
		(fp_line
			(start 0.120396 0.3048)
			(end 0.120396 0.2794)
			(stroke
				(width 0.1)
				(type default)
			)
			(layer "F.Fab")
		)
		(fp_line
			(start 0.67945 0.3048)
			(end 0.120396 0.3048)
			(stroke
				(width 0.1)
				(type default)
			)
			(layer "F.Fab")
		)
		(fp_line
			(start -0.12065 0.2794)
			(end -0.12065 0.3048)
			(stroke
				(width 0.1)
				(type default)
			)
			(layer "F.Fab")
		)
		(fp_line
			(start 0.120396 0.2794)
			(end -0.12065 0.2794)
			(stroke
				(width 0.1)
				(type default)
			)
			(layer "F.Fab")
		)
		(fp_line
			(start -0.12065 -0.2794)
			(end 0.12065 -0.2794)
			(stroke
				(width 0.1)
				(type default)
			)
			(layer "F.Fab")
		)
		(fp_line
			(start 0.12065 -0.2794)
			(end 0.12065 -0.3048)
			(stroke
				(width 0.1)
				(type default)
			)
			(layer "F.Fab")
		)
		(fp_line
			(start 0.12065 -0.3048)
			(end 0.67945 -0.3048)
			(stroke
				(width 0.1)
				(type default)
			)
			(layer "F.Fab")
		)
		(fp_line
			(start 0.67945 -0.3048)
			(end 0.67945 0.3048)
			(stroke
				(width 0.1)
				(type default)
			)
			(layer "F.Fab")
		)
		(fp_line
			(start -0.67945 -0.305054)
			(end -0.12065 -0.305054)
			(stroke
				(width 0.1)
				(type default)
			)
			(layer "F.Fab")
		)
		(fp_line
			(start -0.12065 -0.305054)
			(end -0.12065 -0.2794)
			(stroke
				(width 0.1)
				(type default)
			)
			(layer "F.Fab")
		)
		(pad "1" smd circle
			(at -0.40005 0 270)
			(size 0 0)
			(layers "F.Cu" "F.Mask" "F.Paste")
			(net "GND")
		)
		(pad "2" smd circle
			(at 0.40005 0 270)
			(size 0 0)
			(layers "F.Cu" "F.Mask" "F.Paste")
			(net "GND")
		)
	)
	(footprint ""
		(layer "F.Cu")
		(at 174.112936 -363.249972)
		(property "Reference" "PL14"
			(at 0.844804 -3.134868 0)
			(unlocked yes)
			(layer "F.SilkS")
			(effects
				(font
					(size 0.7874 0.5842)
					(thickness 0.1524)
				)
				(justify left)
			)
		)
		(property "Value" ""
			(at 0 0 0)
			(layer "F.Fab")
			(effects
				(font
					(size 1.27 1.27)
				)
			)
		)
		(duplicate_pad_numbers_are_jumpers no)
		(fp_line
			(start -2.249932 -2.249932)
			(end 2.249932 -2.249932)
			(stroke
				(width 0.1524)
				(type default)
			)
			(layer "F.SilkS")
		)
		(fp_line
			(start -2.249932 -1.3843)
			(end -2.249932 -2.249932)
			(stroke
				(width 0.1524)
				(type default)
			)
			(layer "F.SilkS")
		)
		(fp_line
			(start -2.249932 2.249932)
			(end -2.249932 1.3843)
			(stroke
				(width 0.1524)
				(type default)
			)
			(layer "F.SilkS")
		)
		(fp_line
			(start 2.249932 -2.249932)
			(end 2.249932 -1.3843)
			(stroke
				(width 0.1524)
				(type default)
			)
			(layer "F.SilkS")
		)
		(fp_line
			(start 2.249932 1.3843)
			(end 2.249932 2.249932)
			(stroke
				(width 0.1524)
				(type default)
			)
			(layer "F.SilkS")
		)
		(fp_line
			(start 2.249932 2.249932)
			(end -2.249932 2.249932)
			(stroke
				(width 0.1524)
				(type default)
			)
			(layer "F.SilkS")
		)
		(fp_line
			(start -2.249932 -2.249932)
			(end 2.249932 -2.249932)
			(stroke
				(width 0.1)
				(type default)
			)
			(layer "F.Fab")
		)
		(fp_line
			(start -2.249932 2.249932)
			(end -2.249932 -2.249932)
			(stroke
				(width 0.1)
				(type default)
			)
			(layer "F.Fab")
		)
		(fp_line
			(start 2.249932 -2.249932)
			(end 2.249932 2.249932)
			(stroke
				(width 0.1)
				(type default)
			)
			(layer "F.Fab")
		)
		(fp_line
			(start 2.249932 2.249932)
			(end -2.249932 2.249932)
			(stroke
				(width 0.1)
				(type default)
			)
			(layer "F.Fab")
		)
		(pad "1" smd rect
			(at -1.82499 0)
			(size 1.0668 2.5146)
			(layers "F.Cu" "F.Mask" "F.Paste")
			(net "P12V_AUX")
		)
		(pad "2" smd rect
			(at 1.82499 0)
			(size 1.0668 2.5146)
			(layers "F.Cu" "F.Mask" "F.Paste")
			(net "SW_P12V_PVCCFA_EHV_FIVRA_CPU1_R")
		)
	)
	(footprint ""
		(layer "F.Cu")
		(at 365.308134 -337.955382)
		(property "Reference" "PC275_P0_3"
			(at 0 0 0)
			(layer "F.SilkS")
			(hide yes)
			(effects
				(font
					(size 1.27 1.27)
				)
			)
		)
		(property "Value" ""
			(at 0 0 0)
			(layer "F.Fab")
			(effects
				(font
					(size 1.27 1.27)
				)
			)
		)
		(duplicate_pad_numbers_are_jumpers no)
		(fp_line
			(start -0.7874 -0.4064)
			(end 0.7874 -0.4064)
			(stroke
				(width 0.1524)
				(type default)
			)
			(layer "F.SilkS")
		)
		(fp_line
			(start -0.7874 0.4064)
			(end -0.7874 -0.4064)
			(stroke
				(width 0.1524)
				(type default)
			)
			(layer "F.SilkS")
		)
		(fp_line
			(start 0.7874 -0.4064)
			(end 0.7874 0.4064)
			(stroke
				(width 0.1524)
				(type default)
			)
			(layer "F.SilkS")
		)
		(fp_line
			(start 0.7874 0.4064)
			(end -0.7874 0.4064)
			(stroke
				(width 0.1524)
				(type default)
			)
			(layer "F.SilkS")
		)
		(fp_line
			(start -0.67945 -0.305054)
			(end -0.12065 -0.305054)
			(stroke
				(width 0.1)
				(type default)
			)
			(layer "F.Fab")
		)
		(fp_line
			(start -0.67945 0.3048)
			(end -0.67945 -0.305054)
			(stroke
				(width 0.1)
				(type default)
			)
			(layer "F.Fab")
		)
		(fp_line
			(start -0.12065 -0.305054)
			(end -0.12065 -0.2794)
			(stroke
				(width 0.1)
				(type default)
			)
			(layer "F.Fab")
		)
		(fp_line
			(start -0.12065 -0.2794)
			(end 0.12065 -0.2794)
			(stroke
				(width 0.1)
				(type default)
			)
			(layer "F.Fab")
		)
		(fp_line
			(start -0.12065 0.2794)
			(end -0.12065 0.3048)
			(stroke
				(width 0.1)
				(type default)
			)
			(layer "F.Fab")
		)
		(fp_line
			(start -0.12065 0.3048)
			(end -0.67945 0.3048)
			(stroke
				(width 0.1)
				(type default)
			)
			(layer "F.Fab")
		)
		(fp_line
			(start 0.120396 0.2794)
			(end -0.12065 0.2794)
			(stroke
				(width 0.1)
				(type default)
			)
			(layer "F.Fab")
		)
		(fp_line
			(start 0.120396 0.3048)
			(end 0.120396 0.2794)
			(stroke
				(width 0.1)
				(type default)
			)
			(layer "F.Fab")
		)
		(fp_line
			(start 0.12065 -0.3048)
			(end 0.67945 -0.3048)
			(stroke
				(width 0.1)
				(type default)
			)
			(layer "F.Fab")
		)
		(fp_line
			(start 0.12065 -0.2794)
			(end 0.12065 -0.3048)
			(stroke
				(width 0.1)
				(type default)
			)
			(layer "F.Fab")
		)
		(fp_line
			(start 0.67945 -0.3048)
			(end 0.67945 0.3048)
			(stroke
				(width 0.1)
				(type default)
			)
			(layer "F.Fab")
		)
		(fp_line
			(start 0.67945 0.3048)
			(end 0.120396 0.3048)
			(stroke
				(width 0.1)
				(type default)
			)
			(layer "F.Fab")
		)
		(pad "1" smd circle
			(at -0.40005 0)
			(size 0 0)
			(layers "F.Cu" "F.Mask" "F.Paste")
			(net "SW_P12V_PVCCIN_CPU0_FLT")
		)
		(pad "2" smd circle
			(at 0.40005 0)
			(size 0 0)
			(layers "F.Cu" "F.Mask" "F.Paste")
			(net "GND")
		)
	)
	(footprint ""
		(layer "F.Cu")
		(at 439.49366 -106.38536 90)
		(property "Reference" "C2376"
			(at 0 0 90)
			(layer "F.SilkS")
			(hide yes)
			(effects
				(font
					(size 1.27 1.27)
				)
			)
		)
		(property "Value" ""
			(at 0 0 90)
			(layer "F.Fab")
			(effects
				(font
					(size 1.27 1.27)
				)
			)
		)
		(duplicate_pad_numbers_are_jumpers no)
		(fp_line
			(start 0.7874 -0.4064)
			(end 0.7874 0.4064)
			(stroke
				(width 0.1524)
				(type default)
			)
			(layer "F.SilkS")
		)
		(fp_line
			(start -0.7874 -0.4064)
			(end 0.7874 -0.4064)
			(stroke
				(width 0.1524)
				(type default)
			)
			(layer "F.SilkS")
		)
		(fp_line
			(start 0.7874 0.4064)
			(end -0.7874 0.4064)
			(stroke
				(width 0.1524)
				(type default)
			)
			(layer "F.SilkS")
		)
		(fp_line
			(start -0.7874 0.4064)
			(end -0.7874 -0.4064)
			(stroke
				(width 0.1524)
				(type default)
			)
			(layer "F.SilkS")
		)
		(fp_line
			(start -0.12065 -0.305054)
			(end -0.12065 -0.2794)
			(stroke
				(width 0.1)
				(type default)
			)
			(layer "F.Fab")
		)
		(fp_line
			(start -0.67945 -0.305054)
			(end -0.12065 -0.305054)
			(stroke
				(width 0.1)
				(type default)
			)
			(layer "F.Fab")
		)
		(fp_line
			(start 0.67945 -0.3048)
			(end 0.67945 0.3048)
			(stroke
				(width 0.1)
				(type default)
			)
			(layer "F.Fab")
		)
		(fp_line
			(start 0.12065 -0.3048)
			(end 0.67945 -0.3048)
			(stroke
				(width 0.1)
				(type default)
			)
			(layer "F.Fab")
		)
		(fp_line
			(start 0.12065 -0.2794)
			(end 0.12065 -0.3048)
			(stroke
				(width 0.1)
				(type default)
			)
			(layer "F.Fab")
		)
		(fp_line
			(start -0.12065 -0.2794)
			(end 0.12065 -0.2794)
			(stroke
				(width 0.1)
				(type default)
			)
			(layer "F.Fab")
		)
		(fp_line
			(start 0.120396 0.2794)
			(end -0.12065 0.2794)
			(stroke
				(width 0.1)
				(type default)
			)
			(layer "F.Fab")
		)
		(fp_line
			(start -0.12065 0.2794)
			(end -0.12065 0.3048)
			(stroke
				(width 0.1)
				(type default)
			)
			(layer "F.Fab")
		)
		(fp_line
			(start 0.67945 0.3048)
			(end 0.120396 0.3048)
			(stroke
				(width 0.1)
				(type default)
			)
			(layer "F.Fab")
		)
		(fp_line
			(start 0.120396 0.3048)
			(end 0.120396 0.2794)
			(stroke
				(width 0.1)
				(type default)
			)
			(layer "F.Fab")
		)
		(fp_line
			(start -0.12065 0.3048)
			(end -0.67945 0.3048)
			(stroke
				(width 0.1)
				(type default)
			)
			(layer "F.Fab")
		)
		(fp_line
			(start -0.67945 0.3048)
			(end -0.67945 -0.305054)
			(stroke
				(width 0.1)
				(type default)
			)
			(layer "F.Fab")
		)
		(pad "1" smd circle
			(at -0.40005 0 90)
			(size 0 0)
			(layers "F.Cu" "F.Mask" "F.Paste")
			(net "P3V3_AUX")
		)
		(pad "2" smd circle
			(at 0.40005 0 90)
			(size 0 0)
			(layers "F.Cu" "F.Mask" "F.Paste")
			(net "GND")
		)
	)
	(footprint ""
		(layer "F.Cu")
		(at 159.82188 -58.511948 180)
		(property "Reference" "R1700"
			(at 0 0 180)
			(layer "F.SilkS")
			(hide yes)
			(effects
				(font
					(size 1.27 1.27)
				)
			)
		)
		(property "Value" ""
			(at 0 0 180)
			(layer "F.Fab")
			(effects
				(font
					(size 1.27 1.27)
				)
			)
		)
		(duplicate_pad_numbers_are_jumpers no)
		(fp_line
			(start 0.7874 0.4064)
			(end -0.7874 0.4064)
			(stroke
				(width 0.1524)
				(type default)
			)
			(layer "F.SilkS")
		)
		(fp_line
			(start 0.7874 -0.4064)
			(end 0.7874 0.4064)
			(stroke
				(width 0.1524)
				(type default)
			)
			(layer "F.SilkS")
		)
		(fp_line
			(start -0.7874 0.4064)
			(end -0.7874 -0.4064)
			(stroke
				(width 0.1524)
				(type default)
			)
			(layer "F.SilkS")
		)
		(fp_line
			(start -0.7874 -0.4064)
			(end 0.7874 -0.4064)
			(stroke
				(width 0.1524)
				(type default)
			)
			(layer "F.SilkS")
		)
		(fp_line
			(start 0.67945 0.3048)
			(end 0.120396 0.3048)
			(stroke
				(width 0.1)
				(type default)
			)
			(layer "F.Fab")
		)
		(fp_line
			(start 0.67945 -0.3048)
			(end 0.67945 0.3048)
			(stroke
				(width 0.1)
				(type default)
			)
			(layer "F.Fab")
		)
		(fp_line
			(start 0.12065 -0.2794)
			(end 0.12065 -0.3048)
			(stroke
				(width 0.1)
				(type default)
			)
			(layer "F.Fab")
		)
		(fp_line
			(start 0.12065 -0.3048)
			(end 0.67945 -0.3048)
			(stroke
				(width 0.1)
				(type default)
			)
			(layer "F.Fab")
		)
		(fp_line
			(start 0.120396 0.3048)
			(end 0.120396 0.2794)
			(stroke
				(width 0.1)
				(type default)
			)
			(layer "F.Fab")
		)
		(fp_line
			(start 0.120396 0.2794)
			(end -0.12065 0.2794)
			(stroke
				(width 0.1)
				(type default)
			)
			(layer "F.Fab")
		)
		(fp_line
			(start -0.12065 0.3048)
			(end -0.67945 0.3048)
			(stroke
				(width 0.1)
				(type default)
			)
			(layer "F.Fab")
		)
		(fp_line
			(start -0.12065 0.2794)
			(end -0.12065 0.3048)
			(stroke
				(width 0.1)
				(type default)
			)
			(layer "F.Fab")
		)
		(fp_line
			(start -0.12065 -0.2794)
			(end 0.12065 -0.2794)
			(stroke
				(width 0.1)
				(type default)
			)
			(layer "F.Fab")
		)
		(fp_line
			(start -0.12065 -0.305054)
			(end -0.12065 -0.2794)
			(stroke
				(width 0.1)
				(type default)
			)
			(layer "F.Fab")
		)
		(fp_line
			(start -0.67945 0.3048)
			(end -0.67945 -0.305054)
			(stroke
				(width 0.1)
				(type default)
			)
			(layer "F.Fab")
		)
		(fp_line
			(start -0.67945 -0.305054)
			(end -0.12065 -0.305054)
			(stroke
				(width 0.1)
				(type default)
			)
			(layer "F.Fab")
		)
		(pad "1" smd circle
			(at -0.40005 0 180)
			(size 0 0)
			(layers "F.Cu" "F.Mask" "F.Paste")
			(net "P3V3_AUX")
		)
		(pad "2" smd circle
			(at 0.40005 0 180)
			(size 0 0)
			(layers "F.Cu" "F.Mask" "F.Paste")
			(net "SMB_PCIE_M2_0_EN")
		)
	)
	(footprint ""
		(layer "F.Cu")
		(at 325.860156 -251.76988)
		(property "Reference" "H25"
			(at -5.439156 -4.581398 0)
			(unlocked yes)
			(layer "F.SilkS")
			(effects
				(font
					(size 0.7874 0.5842)
					(thickness 0.1524)
				)
				(justify left)
			)
		)
		(property "Value" ""
			(at 0 0 0)
			(layer "F.Fab")
			(effects
				(font
					(size 1.27 1.27)
				)
			)
		)
		(duplicate_pad_numbers_are_jumpers no)
		(fp_circle
			(center 0 0)
			(end 2.5273 0)
			(stroke
				(width 0.1524)
				(type default)
			)
			(fill no)
			(layer "F.SilkS")
		)
		(fp_circle
			(center 0 0)
			(end 2.5273 0)
			(stroke
				(width 0.1524)
				(type default)
			)
			(fill no)
			(layer "B.SilkS")
		)
		(fp_circle
			(center 0 0)
			(end 2.5273 0)
			(stroke
				(width 0.1)
				(type default)
			)
			(fill no)
			(layer "B.Fab")
		)
		(fp_circle
			(center 0 0)
			(end 2.5273 0)
			(stroke
				(width 0.1)
				(type default)
			)
			(fill no)
			(layer "F.Fab")
		)
		(pad "" np_thru_hole circle
			(at 0 0)
			(size 3.429 3.429)
			(drill 3.429)
			(layers "*.Cu" "*.Mask")
			(clearance 0.381)
			(thermal_gap 0.381)
		)
	)
	(footprint ""
		(layer "F.Cu")
		(at 104.347264 -258.72694 90)
		(property "Reference" "C444"
			(at 0 0 90)
			(layer "F.SilkS")
			(hide yes)
			(effects
				(font
					(size 1.27 1.27)
				)
			)
		)
		(property "Value" ""
			(at 0 0 90)
			(layer "F.Fab")
			(effects
				(font
					(size 1.27 1.27)
				)
			)
		)
		(duplicate_pad_numbers_are_jumpers no)
		(fp_line
			(start 0.7874 -0.4064)
			(end 0.7874 0.4064)
			(stroke
				(width 0.1524)
				(type default)
			)
			(layer "F.SilkS")
		)
		(fp_line
			(start -0.7874 -0.4064)
			(end 0.7874 -0.4064)
			(stroke
				(width 0.1524)
				(type default)
			)
			(layer "F.SilkS")
		)
		(fp_line
			(start 0.7874 0.4064)
			(end -0.7874 0.4064)
			(stroke
				(width 0.1524)
				(type default)
			)
			(layer "F.SilkS")
		)
		(fp_line
			(start -0.7874 0.4064)
			(end -0.7874 -0.4064)
			(stroke
				(width 0.1524)
				(type default)
			)
			(layer "F.SilkS")
		)
		(fp_line
			(start -0.12065 -0.305054)
			(end -0.12065 -0.2794)
			(stroke
				(width 0.1)
				(type default)
			)
			(layer "F.Fab")
		)
		(fp_line
			(start -0.67945 -0.305054)
			(end -0.12065 -0.305054)
			(stroke
				(width 0.1)
				(type default)
			)
			(layer "F.Fab")
		)
		(fp_line
			(start 0.67945 -0.3048)
			(end 0.67945 0.3048)
			(stroke
				(width 0.1)
				(type default)
			)
			(layer "F.Fab")
		)
		(fp_line
			(start 0.12065 -0.3048)
			(end 0.67945 -0.3048)
			(stroke
				(width 0.1)
				(type default)
			)
			(layer "F.Fab")
		)
		(fp_line
			(start 0.12065 -0.2794)
			(end 0.12065 -0.3048)
			(stroke
				(width 0.1)
				(type default)
			)
			(layer "F.Fab")
		)
		(fp_line
			(start -0.12065 -0.2794)
			(end 0.12065 -0.2794)
			(stroke
				(width 0.1)
				(type default)
			)
			(layer "F.Fab")
		)
		(fp_line
			(start 0.120396 0.2794)
			(end -0.12065 0.2794)
			(stroke
				(width 0.1)
				(type default)
			)
			(layer "F.Fab")
		)
		(fp_line
			(start -0.12065 0.2794)
			(end -0.12065 0.3048)
			(stroke
				(width 0.1)
				(type default)
			)
			(layer "F.Fab")
		)
		(fp_line
			(start 0.67945 0.3048)
			(end 0.120396 0.3048)
			(stroke
				(width 0.1)
				(type default)
			)
			(layer "F.Fab")
		)
		(fp_line
			(start 0.120396 0.3048)
			(end 0.120396 0.2794)
			(stroke
				(width 0.1)
				(type default)
			)
			(layer "F.Fab")
		)
		(fp_line
			(start -0.12065 0.3048)
			(end -0.67945 0.3048)
			(stroke
				(width 0.1)
				(type default)
			)
			(layer "F.Fab")
		)
		(fp_line
			(start -0.67945 0.3048)
			(end -0.67945 -0.305054)
			(stroke
				(width 0.1)
				(type default)
			)
			(layer "F.Fab")
		)
		(pad "1" smd circle
			(at -0.40005 0 90)
			(size 0 0)
			(layers "F.Cu" "F.Mask" "F.Paste")
			(net "PVCCFA_EHV_CPU1")
		)
		(pad "2" smd circle
			(at 0.40005 0 90)
			(size 0 0)
			(layers "F.Cu" "F.Mask" "F.Paste")
			(net "GND")
		)
	)
	(footprint ""
		(layer "F.Cu")
		(at 94.899988 -22.29993)
		(property "Reference" "H101"
			(at -6.23824 -4.478528 0)
			(unlocked yes)
			(layer "F.SilkS")
			(effects
				(font
					(size 0.7874 0.5842)
					(thickness 0.1524)
				)
				(justify left)
			)
		)
		(property "Value" ""
			(at 0 0 0)
			(layer "F.Fab")
			(effects
				(font
					(size 1.27 1.27)
				)
			)
		)
		(duplicate_pad_numbers_are_jumpers no)
		(pad "1" thru_hole circle
			(at 0 0)
			(size 10.0076 10.0076)
			(drill 5.6134)
			(layers "*.Cu" "*.Mask")
			(remove_unused_layers no)
			(net "GND")
			(clearance -1.9431)
		)
	)
)
